(kicad_pcb
	(version 20260206)
	(generator "pcbnew")
	(generator_version "10.0")
	(general
		(thickness 1.6)
		(legacy_teardrops no)
	)
	(paper "A4")
	(title_block
		(title "12092022_DA0F0TFB6D0_F0T_FAN_BOARD_MP5048_D_brd_v02_OCP.brd")
		(comment 1 "Grand Teton / footprints 743-746 of 924")
	)
	(layers
		(0 "F.Cu" signal "TOP")
		(4 "In1.Cu" signal "GND")
		(6 "In2.Cu" signal "IN1")
		(8 "In3.Cu" signal "IN2")
		(10 "In4.Cu" signal "GND1")
		(2 "B.Cu" signal "BOTTOM")
		(9 "F.Adhes" user "F.Adhesive")
		(11 "B.Adhes" user "B.Adhesive")
		(13 "F.Paste" user "Package Geometry/Pastemask Top")
		(15 "B.Paste" user "Package Geometry/Pastemask Bottom")
		(5 "F.SilkS" user "Ref Des/Silkscreen Top")
		(7 "B.SilkS" user "Ref Des/Silkscreen Bottom")
		(1 "F.Mask" user "Board Geometry/Soldermask Top")
		(3 "B.Mask" user "Board Geometry/Soldermask Bottom")
		(17 "Dwgs.User" user "User.Drawings")
		(19 "Cmts.User" user "User.Comments")
		(21 "Eco1.User" user "User.Eco1")
		(23 "Eco2.User" user "User.Eco2")
		(25 "Edge.Cuts" user "Board Geometry/Outline")
		(27 "Margin" user)
		(31 "F.CrtYd" user "Package Geometry/Place Bound Top")
		(29 "B.CrtYd" user "Package Geometry/Place Bound Bottom")
		(35 "F.Fab" user "Ref Des/Assembly Top")
		(33 "B.Fab" user "Ref Des/Assembly Bottom")
	)
	(footprint ""
		(layer "B.Cu")
		(at 44.99991 -26.409904)
		(property "Reference" "J4"
			(at 4.384802 -5.317744 0)
			(unlocked yes)
			(layer "B.SilkS")
			(effects
				(font
					(size 0.7874 0.5842)
					(thickness 0.1524)
				)
				(justify left mirror)
			)
		)
		(property "Value" ""
			(at 0 0 0)
			(layer "B.Fab")
			(effects
				(font
					(size 1.27 1.27)
				)
				(justify mirror)
			)
		)
		(duplicate_pad_numbers_are_jumpers no)
		(fp_line
			(start -6.35 -4.52501)
			(end 4.350004 -4.52501)
			(stroke
				(width 0.1524)
				(type default)
			)
			(layer "B.SilkS")
		)
		(fp_line
			(start -6.35 18.524982)
			(end -6.35 -4.52501)
			(stroke
				(width 0.1524)
				(type default)
			)
			(layer "B.SilkS")
		)
		(fp_line
			(start -3.24993 -1.42494)
			(end -1.96977 -1.42494)
			(stroke
				(width 0.1524)
				(type default)
			)
			(layer "B.SilkS")
		)
		(fp_line
			(start -3.24993 15.424912)
			(end -3.24993 -1.42494)
			(stroke
				(width 0.1524)
				(type default)
			)
			(layer "B.SilkS")
		)
		(fp_line
			(start -0.029972 -1.42494)
			(end 1.249934 -1.42494)
			(stroke
				(width 0.1524)
				(type default)
			)
			(layer "B.SilkS")
		)
		(fp_line
			(start 1.249934 -1.42494)
			(end 1.249934 5.799836)
			(stroke
				(width 0.1524)
				(type default)
			)
			(layer "B.SilkS")
		)
		(fp_line
			(start 1.249934 5.799836)
			(end 4.350004 5.799836)
			(stroke
				(width 0.1524)
				(type default)
			)
			(layer "B.SilkS")
		)
		(fp_line
			(start 1.249934 8.200136)
			(end 1.249934 15.424912)
			(stroke
				(width 0.1524)
				(type default)
			)
			(layer "B.SilkS")
		)
		(fp_line
			(start 1.249934 8.200136)
			(end 4.350004 8.200136)
			(stroke
				(width 0.1524)
				(type default)
			)
			(layer "B.SilkS")
		)
		(fp_line
			(start 1.249934 15.424912)
			(end -3.24993 15.424912)
			(stroke
				(width 0.1524)
				(type default)
			)
			(layer "B.SilkS")
		)
		(fp_line
			(start 4.350004 -4.52501)
			(end 4.350004 18.524982)
			(stroke
				(width 0.1524)
				(type default)
			)
			(layer "B.SilkS")
		)
		(fp_line
			(start 4.350004 18.524982)
			(end -6.35 18.524982)
			(stroke
				(width 0.1524)
				(type default)
			)
			(layer "B.SilkS")
		)
		(fp_poly
			(pts
				(xy 5.527802 -0.508) (xy 5.527802 0.508) (xy 4.511802 0)
			)
			(stroke
				(width 0)
				(type default)
			)
			(fill yes)
			(layer "B.SilkS")
		)
		(fp_line
			(start -6.35 -4.52501)
			(end 4.350004 -4.52501)
			(stroke
				(width 0.1)
				(type default)
			)
			(layer "B.Fab")
		)
		(fp_line
			(start -6.35 18.524982)
			(end -6.35 -4.52501)
			(stroke
				(width 0.1)
				(type default)
			)
			(layer "B.Fab")
		)
		(fp_line
			(start 4.350004 -4.52501)
			(end 4.350004 18.524982)
			(stroke
				(width 0.1)
				(type default)
			)
			(layer "B.Fab")
		)
		(fp_line
			(start 4.350004 18.524982)
			(end -6.35 18.524982)
			(stroke
				(width 0.1)
				(type default)
			)
			(layer "B.Fab")
		)
		(fp_poly
			(pts
				(xy 5.527802 -0.508) (xy 5.527802 0.508) (xy 4.511802 0)
			)
			(stroke
				(width 0)
				(type default)
			)
			(fill yes)
			(layer "B.Fab")
		)
		(pad "" np_thru_hole circle
			(at -0.999998 -1.89992 270)
			(size 1.4986 1.4986)
			(drill 1.4986)
			(layers "*.Cu" "*.Mask")
			(clearance 0.381)
			(thermal_gap 0.381)
		)
		(pad "1" thru_hole rect
			(at 0 0 270)
			(size 1.3716 1.3716)
			(drill 0.9652)
			(layers "*.Cu" "*.Mask")
			(remove_unused_layers no)
			(net "FAN_3_TACH_IL_D")
			(clearance 0.0508)
			(padstack
				(mode front_inner_back)
				(layer "Inner"
					(shape circle)
					(size 1.3716 1.3716)
					(clearance 0.0508)
				)
				(layer "B.Cu"
					(shape rect)
					(size 1.3716 1.3716)
					(thermal_gap 0.0508)
					(clearance 0.0508)
				)
			)
		)
		(pad "2" thru_hole circle
			(at -1.999996 0 270)
			(size 1.3716 1.3716)
			(drill 0.9652)
			(layers "*.Cu" "*.Mask")
			(remove_unused_layers no)
			(net "FAN_3_PWM_OL_R")
			(clearance 0.0508)
			(thermal_gap 0.0508)
		)
		(pad "3" thru_hole circle
			(at 0 1.999996 270)
			(size 1.3716 1.3716)
			(drill 0.9652)
			(layers "*.Cu" "*.Mask")
			(remove_unused_layers no)
			(net "FAN_3_PWM_IL_R")
			(clearance 0.0508)
			(thermal_gap 0.0508)
		)
		(pad "4" thru_hole circle
			(at -1.999996 1.999996 270)
			(size 1.3716 1.3716)
			(drill 0.9652)
			(layers "*.Cu" "*.Mask")
			(remove_unused_layers no)
			(net "FAN_3_PRESENT_R_N")
			(clearance 0.0508)
			(thermal_gap 0.0508)
		)
		(pad "5" thru_hole circle
			(at 0 3.999992 270)
			(size 1.3716 1.3716)
			(drill 0.9652)
			(layers "*.Cu" "*.Mask")
			(remove_unused_layers no)
			(net "P12V_LED_R1_FAN3")
			(clearance 0.0508)
			(thermal_gap 0.0508)
		)
		(pad "6" thru_hole circle
			(at -1.999996 3.999992 270)
			(size 1.3716 1.3716)
			(drill 0.9652)
			(layers "*.Cu" "*.Mask")
			(remove_unused_layers no)
			(net "SMB_FAN3_SCL_R")
			(clearance 0.0508)
			(thermal_gap 0.0508)
		)
		(pad "7" thru_hole circle
			(at 0 5.999988 270)
			(size 1.3716 1.3716)
			(drill 0.9652)
			(layers "*.Cu" "*.Mask")
			(remove_unused_layers no)
			(net "SMB_FAN3_SDA_R")
			(clearance 0.0508)
			(thermal_gap 0.0508)
		)
		(pad "8" thru_hole circle
			(at -1.999996 5.999988 270)
			(size 1.3716 1.3716)
			(drill 0.9652)
			(layers "*.Cu" "*.Mask")
			(remove_unused_layers no)
			(net "GND")
			(clearance 0.0508)
			(thermal_gap 0.0508)
		)
		(pad "9" thru_hole circle
			(at 0 7.999984 270)
			(size 1.3716 1.3716)
			(drill 0.9652)
			(layers "*.Cu" "*.Mask")
			(remove_unused_layers no)
			(net "GND")
			(clearance 0.0508)
			(thermal_gap 0.0508)
		)
		(pad "10" thru_hole circle
			(at -1.999996 7.999984 270)
			(size 1.3716 1.3716)
			(drill 0.9652)
			(layers "*.Cu" "*.Mask")
			(remove_unused_layers no)
			(net "P52V_FAN_3")
			(clearance 0.0508)
			(thermal_gap 0.0508)
		)
		(pad "11" thru_hole circle
			(at 0 9.99998 270)
			(size 1.3716 1.3716)
			(drill 0.9652)
			(layers "*.Cu" "*.Mask")
			(remove_unused_layers no)
			(net "P52V_FAN_3")
			(clearance 0.0508)
			(thermal_gap 0.0508)
		)
		(pad "12" thru_hole circle
			(at -1.999996 9.99998 270)
			(size 1.3716 1.3716)
			(drill 0.9652)
			(layers "*.Cu" "*.Mask")
			(remove_unused_layers no)
			(net "FAN_3_FAIL_R_LED_N")
			(clearance 0.0508)
			(thermal_gap 0.0508)
		)
		(pad "13" thru_hole circle
			(at 0 11.999976 270)
			(size 1.3716 1.3716)
			(drill 0.9652)
			(layers "*.Cu" "*.Mask")
			(remove_unused_layers no)
			(net "FAN_3_TACH_OL_D")
			(clearance 0.0508)
			(thermal_gap 0.0508)
		)
		(pad "14" thru_hole circle
			(at -1.999996 11.999976 270)
			(size 1.3716 1.3716)
			(drill 0.9652)
			(layers "*.Cu" "*.Mask")
			(remove_unused_layers no)
			(net "FAN_3_OK_R_LED_N")
			(clearance 0.0508)
			(thermal_gap 0.0508)
		)
		(pad "15" thru_hole circle
			(at 0 13.999972 270)
			(size 1.3716 1.3716)
			(drill 0.9652)
			(layers "*.Cu" "*.Mask")
			(remove_unused_layers no)
			(net "Net_609")
			(clearance 0.0508)
			(thermal_gap 0.0508)
		)
		(pad "16" thru_hole circle
			(at -1.999996 13.999972 270)
			(size 1.3716 1.3716)
			(drill 0.9652)
			(layers "*.Cu" "*.Mask")
			(remove_unused_layers no)
			(net "Net_608")
			(clearance 0.0508)
			(thermal_gap 0.0508)
		)
		(zone
			(layers "F.Cu" "B.Cu" "In1.Cu" "In2.Cu" "In3.Cu" "In4.Cu")
			(hatch none 0.5)
			(connect_pads
				(clearance 0)
			)
			(min_thickness 0.25)
			(keepout
				(tracks not_allowed)
				(vias allowed)
				(pads allowed)
				(copperpour not_allowed)
				(footprints allowed)
			)
			(placement
				(enabled no)
				(sheetname "")
			)
			(fill
				(thermal_gap 0.5)
				(thermal_bridge_width 0.5)
				(island_removal_mode 0)
			)
			(polygon
				(pts
					(arc
						(start 45.257212 -28.309824)
						(mid 42.742612 -28.309824)
						(end 45.257212 -28.309824)
					)
				)
			)
		)
	)
	(footprint ""
		(layer "B.Cu")
		(at 7.62 -64.837056 -90)
		(property "Reference" "PC38"
			(at 0 0 90)
			(layer "B.SilkS")
			(hide yes)
			(effects
				(font
					(size 1.27 1.27)
				)
				(justify mirror)
			)
		)
		(property "Value" ""
			(at 0 0 90)
			(layer "B.Fab")
			(effects
				(font
					(size 1.27 1.27)
				)
				(justify mirror)
			)
		)
		(duplicate_pad_numbers_are_jumpers no)
		(fp_line
			(start -0.7874 0.4064)
			(end 0.7874 0.4064)
			(stroke
				(width 0.1524)
				(type default)
			)
			(layer "B.SilkS")
		)
		(fp_line
			(start 0.7874 0.4064)
			(end 0.7874 -0.4064)
			(stroke
				(width 0.1524)
				(type default)
			)
			(layer "B.SilkS")
		)
		(fp_line
			(start -0.7874 -0.4064)
			(end -0.7874 0.4064)
			(stroke
				(width 0.1524)
				(type default)
			)
			(layer "B.SilkS")
		)
		(fp_line
			(start 0.7874 -0.4064)
			(end -0.7874 -0.4064)
			(stroke
				(width 0.1524)
				(type default)
			)
			(layer "B.SilkS")
		)
		(fp_line
			(start -0.67945 0.3048)
			(end -0.120396 0.3048)
			(stroke
				(width 0.1)
				(type default)
			)
			(layer "B.Fab")
		)
		(fp_line
			(start -0.120396 0.3048)
			(end -0.120396 0.2794)
			(stroke
				(width 0.1)
				(type default)
			)
			(layer "B.Fab")
		)
		(fp_line
			(start 0.12065 0.3048)
			(end 0.67945 0.3048)
			(stroke
				(width 0.1)
				(type default)
			)
			(layer "B.Fab")
		)
		(fp_line
			(start 0.67945 0.3048)
			(end 0.67945 -0.305054)
			(stroke
				(width 0.1)
				(type default)
			)
			(layer "B.Fab")
		)
		(fp_line
			(start -0.120396 0.2794)
			(end 0.12065 0.2794)
			(stroke
				(width 0.1)
				(type default)
			)
			(layer "B.Fab")
		)
		(fp_line
			(start 0.12065 0.2794)
			(end 0.12065 0.3048)
			(stroke
				(width 0.1)
				(type default)
			)
			(layer "B.Fab")
		)
		(fp_line
			(start -0.12065 -0.2794)
			(end -0.12065 -0.3048)
			(stroke
				(width 0.1)
				(type default)
			)
			(layer "B.Fab")
		)
		(fp_line
			(start 0.12065 -0.2794)
			(end -0.12065 -0.2794)
			(stroke
				(width 0.1)
				(type default)
			)
			(layer "B.Fab")
		)
		(fp_line
			(start -0.67945 -0.3048)
			(end -0.67945 0.3048)
			(stroke
				(width 0.1)
				(type default)
			)
			(layer "B.Fab")
		)
		(fp_line
			(start -0.12065 -0.3048)
			(end -0.67945 -0.3048)
			(stroke
				(width 0.1)
				(type default)
			)
			(layer "B.Fab")
		)
		(fp_line
			(start 0.12065 -0.305054)
			(end 0.12065 -0.2794)
			(stroke
				(width 0.1)
				(type default)
			)
			(layer "B.Fab")
		)
		(fp_line
			(start 0.67945 -0.305054)
			(end 0.12065 -0.305054)
			(stroke
				(width 0.1)
				(type default)
			)
			(layer "B.Fab")
		)
		(pad "1" smd circle
			(at 0.40005 0 90)
			(size 0 0)
			(layers "B.Cu" "B.Mask" "B.Paste")
			(net "FAN_4_P3V_R")
		)
		(pad "2" smd circle
			(at -0.40005 0 90)
			(size 0 0)
			(layers "B.Cu" "B.Mask" "B.Paste")
			(net "GND")
		)
	)
	(footprint ""
		(layer "B.Cu")
		(at 37.211 -250.23699 90)
		(property "Reference" "PC3119"
			(at 0 0 90)
			(layer "B.SilkS")
			(hide yes)
			(effects
				(font
					(size 1.27 1.27)
				)
				(justify mirror)
			)
		)
		(property "Value" ""
			(at 0 0 90)
			(layer "B.Fab")
			(effects
				(font
					(size 1.27 1.27)
				)
				(justify mirror)
			)
		)
		(duplicate_pad_numbers_are_jumpers no)
		(fp_line
			(start 0.7874 -0.4064)
			(end -0.7874 -0.4064)
			(stroke
				(width 0.1524)
				(type default)
			)
			(layer "B.SilkS")
		)
		(fp_line
			(start -0.7874 -0.4064)
			(end -0.7874 0.4064)
			(stroke
				(width 0.1524)
				(type default)
			)
			(layer "B.SilkS")
		)
		(fp_line
			(start 0.7874 0.4064)
			(end 0.7874 -0.4064)
			(stroke
				(width 0.1524)
				(type default)
			)
			(layer "B.SilkS")
		)
		(fp_line
			(start -0.7874 0.4064)
			(end 0.7874 0.4064)
			(stroke
				(width 0.1524)
				(type default)
			)
			(layer "B.SilkS")
		)
		(fp_line
			(start 0.67945 -0.305054)
			(end 0.12065 -0.305054)
			(stroke
				(width 0.1)
				(type default)
			)
			(layer "B.Fab")
		)
		(fp_line
			(start 0.12065 -0.305054)
			(end 0.12065 -0.2794)
			(stroke
				(width 0.1)
				(type default)
			)
			(layer "B.Fab")
		)
		(fp_line
			(start -0.12065 -0.3048)
			(end -0.67945 -0.3048)
			(stroke
				(width 0.1)
				(type default)
			)
			(layer "B.Fab")
		)
		(fp_line
			(start -0.67945 -0.3048)
			(end -0.67945 0.3048)
			(stroke
				(width 0.1)
				(type default)
			)
			(layer "B.Fab")
		)
		(fp_line
			(start 0.12065 -0.2794)
			(end -0.12065 -0.2794)
			(stroke
				(width 0.1)
				(type default)
			)
			(layer "B.Fab")
		)
		(fp_line
			(start -0.12065 -0.2794)
			(end -0.12065 -0.3048)
			(stroke
				(width 0.1)
				(type default)
			)
			(layer "B.Fab")
		)
		(fp_line
			(start 0.12065 0.2794)
			(end 0.12065 0.3048)
			(stroke
				(width 0.1)
				(type default)
			)
			(layer "B.Fab")
		)
		(fp_line
			(start -0.120396 0.2794)
			(end 0.12065 0.2794)
			(stroke
				(width 0.1)
				(type default)
			)
			(layer "B.Fab")
		)
		(fp_line
			(start 0.67945 0.3048)
			(end 0.67945 -0.305054)
			(stroke
				(width 0.1)
				(type default)
			)
			(layer "B.Fab")
		)
		(fp_line
			(start 0.12065 0.3048)
			(end 0.67945 0.3048)
			(stroke
				(width 0.1)
				(type default)
			)
			(layer "B.Fab")
		)
		(fp_line
			(start -0.120396 0.3048)
			(end -0.120396 0.2794)
			(stroke
				(width 0.1)
				(type default)
			)
			(layer "B.Fab")
		)
		(fp_line
			(start -0.67945 0.3048)
			(end -0.120396 0.3048)
			(stroke
				(width 0.1)
				(type default)
			)
			(layer "B.Fab")
		)
		(pad "1" smd circle
			(at 0.40005 0 270)
			(size 0 0)
			(layers "B.Cu" "B.Mask" "B.Paste")
			(net "GND")
		)
		(pad "2" smd circle
			(at -0.40005 0 270)
			(size 0 0)
			(layers "B.Cu" "B.Mask" "B.Paste")
			(net "FAN_1_CLREF")
		)
	)
	(footprint ""
		(layer "B.Cu")
		(at 46.6852 -247.8278 90)
		(property "Reference" "PD4"
			(at -5.5372 3.88493 270)
			(unlocked yes)
			(layer "B.SilkS")
			(effects
				(font
					(size 0.7874 0.5842)
					(thickness 0.1524)
				)
				(justify left mirror)
			)
		)
		(property "Value" ""
			(at 0 0 90)
			(layer "B.Fab")
			(effects
				(font
					(size 1.27 1.27)
				)
				(justify mirror)
			)
		)
		(duplicate_pad_numbers_are_jumpers no)
		(fp_line
			(start 4.647184 -3.109976)
			(end 4.647184 3.109976)
			(stroke
				(width 0.1524)
				(type default)
			)
			(layer "B.SilkS")
		)
		(fp_line
			(start -5.536184 -3.109976)
			(end 4.647184 -3.109976)
			(stroke
				(width 0.1524)
				(type default)
			)
			(layer "B.SilkS")
		)
		(fp_line
			(start -0.762 -1.143)
			(end -0.762 0.889)
			(stroke
				(width 0.1524)
				(type default)
			)
			(layer "B.SilkS")
		)
		(fp_line
			(start 0.635 -0.889)
			(end 0.635 0.635)
			(stroke
				(width 0.1524)
				(type default)
			)
			(layer "B.SilkS")
		)
		(fp_line
			(start 1.397 -0.127)
			(end 0.635 -0.127)
			(stroke
				(width 0.1524)
				(type default)
			)
			(layer "B.SilkS")
		)
		(fp_line
			(start -0.635 -0.127)
			(end 0.635 -0.889)
			(stroke
				(width 0.1524)
				(type default)
			)
			(layer "B.SilkS")
		)
		(fp_line
			(start -0.635 -0.127)
			(end -1.397 -0.127)
			(stroke
				(width 0.1524)
				(type default)
			)
			(layer "B.SilkS")
		)
		(fp_line
			(start 0.635 0.635)
			(end -0.635 -0.127)
			(stroke
				(width 0.1524)
				(type default)
			)
			(layer "B.SilkS")
		)
		(fp_line
			(start 4.647184 3.109976)
			(end -5.536184 3.109976)
			(stroke
				(width 0.1524)
				(type default)
			)
			(layer "B.SilkS")
		)
		(fp_line
			(start -5.536184 3.109976)
			(end -5.536184 -3.109976)
			(stroke
				(width 0.1524)
				(type default)
			)
			(layer "B.SilkS")
		)
		(fp_poly
			(pts
				(xy -5.5118 -3.0988) (xy -5.5118 3.1496) (xy -4.572 3.1496) (xy -4.572 -3.0988)
			)
			(stroke
				(width 0)
				(type default)
			)
			(fill yes)
			(layer "B.SilkS")
		)
		(fp_line
			(start 3.554984 -3.109976)
			(end 3.554984 3.109976)
			(stroke
				(width 0.1)
				(type default)
			)
			(layer "B.Fab")
		)
		(fp_line
			(start -3.554984 -3.109976)
			(end 3.554984 -3.109976)
			(stroke
				(width 0.1)
				(type default)
			)
			(layer "B.Fab")
		)
		(fp_line
			(start 3.554984 3.109976)
			(end -3.554984 3.109976)
			(stroke
				(width 0.1)
				(type default)
			)
			(layer "B.Fab")
		)
		(fp_line
			(start -3.554984 3.109976)
			(end -3.554984 -3.109976)
			(stroke
				(width 0.1)
				(type default)
			)
			(layer "B.Fab")
		)
		(fp_text user "+"
			(at 6.0452 -1.94945 90)
			(unlocked yes)
			(layer "B.SilkS")
			(effects
				(font
					(size 1.905 1.4224)
					(thickness 0.1524)
				)
				(justify left mirror)
			)
		)
		(fp_text user "-"
			(at -5.5118 -1.56845 90)
			(unlocked yes)
			(layer "B.SilkS")
			(effects
				(font
					(size 1.905 1.4224)
					(thickness 0.1524)
				)
				(justify left mirror)
			)
		)
		(fp_text user "-"
			(at -5.334 -0.34925 90)
			(unlocked yes)
			(layer "B.Fab")
			(effects
				(font
					(size 1.905 1.4224)
					(thickness 0.1524)
				)
				(justify left mirror)
			)
		)
		(fp_text user "+"
			(at 6.1214 -0.32385 90)
			(unlocked yes)
			(layer "B.Fab")
			(effects
				(font
					(size 1.905 1.4224)
					(thickness 0.1524)
				)
				(justify left mirror)
			)
		)
		(pad "A" smd rect
			(at 3.299968 0 270)
			(size 2.413 3.302)
			(layers "B.Cu" "B.Mask" "B.Paste")
			(net "GND")
		)
		(pad "C" smd rect
			(at -3.299968 0 270)
			(size 2.413 3.302)
			(layers "B.Cu" "B.Mask" "B.Paste")
			(net "P52V_HSC")
		)
	)
)
